# S9S_MB_2U (Grand Teton) — schematic netlist excerpt (pin names and nets, part order shuffled) for the footprints in the layout excerpt that follows; sources: Cadence DE-HDL packaged netlist, KiCad conversion of 03242023_DA0F0TMBIJ0_F0T_Motherboard_J_brd_V01_OCP.brd

J17  SCONN288_ADR50017P130CC  SCONN288_ADR50017-P130CC IO  pkg DDR288S_1-1VXB  page 98
  VIN_BULK0  = P12V_S3_AUX_CPU1_NVDIMM
  RFU0  = TP_CHA_CPU1_DIMM1_FRU_0
  VIN_MGMT  = P3V3_AUX
  HSCL  = I3C_SPD_DDRABCD_CPU1_LVC1_SCL_R
  HSDA  = I3C_SPD_DDRABCD_CPU1_LVC1_SDA
  VSS0  = GND
  DQ0_A  = M_A_CPU1_SA_DQ<0>
  VSS1  = GND
  DQ1_A  = M_A_CPU1_SA_DQ<1>
  VSS2  = GND
  DQS0_A_T  = M_A_CPU1_SA_DQS_DP<0>
  DQS0_A_C  = M_A_CPU1_SA_DQS_DN<0>
  VSS3  = GND
  DQ4_A  = M_A_CPU1_SA_DQ<4>
  VSS4  = GND
  DQ5_A  = M_A_CPU1_SA_DQ<5>
  VSS5  = GND
  DQ8_A  = M_A_CPU1_SA_DQ<8>
  VSS6  = GND
  DQ9_A  = M_A_CPU1_SA_DQ<9>
  VSS7  = GND
  DQS1_A_T  = M_A_CPU1_SA_DQS_DP<1>
  DQS1_A_C  = M_A_CPU1_SA_DQS_DN<1>
  VSS8  = GND
  DQ12_A  = M_A_CPU1_SA_DQ<12>
  VSS9  = GND
  DQ13_A  = M_A_CPU1_SA_DQ<13>
  VSS10  = GND
  DQ16_A  = M_A_CPU1_SA_DQ<16>
  VSS11  = GND
  DQ17_A  = M_A_CPU1_SA_DQ<17>
  VSS12  = GND
  DQS2_A_T  = M_A_CPU1_SA_DQS_DP<2>
  DQS2_A_C  = M_A_CPU1_SA_DQS_DN<2>
  VSS13  = GND
  DQ20_A  = M_A_CPU1_SA_DQ<20>
  VSS14  = GND
  DQ21_A  = M_A_CPU1_SA_DQ<21>
  VSS15  = GND
  DQ24_A  = M_A_CPU1_SA_DQ<24>
  VSS16  = GND
  DQ25_A  = M_A_CPU1_SA_DQ<25>
  VSS17  = GND
  DQS3_A_T  = M_A_CPU1_SA_DQS_DP<3>
  DQS3_A_C  = M_A_CPU1_SA_DQS_DN<3>
  VSS18  = GND
  DQ28_A  = M_A_CPU1_SA_DQ<28>
  VSS19  = GND
  DQ29_A  = M_A_CPU1_SA_DQ<29>
  VSS20  = GND
  CB0_A  = M_A_CPU1_SA_CB<0>
  VSS21  = GND
  CB1_A  = M_A_CPU1_SA_CB<1>
  VSS22  = GND
  DQS4_A_T  = M_A_CPU1_SA_DQS_DP<4>
  DQS4_A_C  = M_A_CPU1_SA_DQS_DN<4>
  VSS23  = GND
  CB4_A  = M_A_CPU1_SA_CB<4>
  VSS24  = GND
  CB5_A  = M_A_CPU1_SA_CB<5>
  VSS25  = GND
  ALERT_N  = M_A_CPU1_ALERT_N
  VSS26  = GND
  CS0_A_N  = M_A_CPU1_SA_CS_N<0>
  VSS27  = GND
  CA0_A  = M_A_CPU1_SA_CA<0>
  VSS28  = GND
  CA2_A  = M_A_CPU1_SA_CA<2>
  VSS29  = GND
  CA4_A  = M_A_CPU1_SA_CA<4>
  VSS30  = GND
  CA6_A  = M_A_CPU1_SA_CA<6>
  VSS31  = GND
  PAR_A  = M_A_CPU1_SA_PAR
  VSS32  = GND
  CA0_B  = M_A_CPU1_SB_CA<0>
  VSS33  = GND
  CA2_B  = M_A_CPU1_SB_CA<2>
  VSS34  = GND
  CA4_B  = M_A_CPU1_SB_CA<4>
  VSS35  = GND
  CA6_B  = M_A_CPU1_SB_CA<6>
  VSS36  = GND
  CS0_B_N  = M_A_CPU1_SB_CS_N<0>
  VSS37  = GND
  \lbd||rsp_a_n\  = M_A_CPU1_SA_RSP<0>
  \lbs||rsp_b_n\  = M_A_CPU1_SB_RSP<0>
  VSS38  = GND
  CB4_B  = M_A_CPU1_SB_CB<4>
  VSS39  = GND
  CB5_B  = M_A_CPU1_SB_CB<5>
  VSS40  = GND
  \dqs9_b_t||tdqs9_b_t||dbi4_b_n\  = M_A_CPU1_SB_DQS_DP<9>
  \dqs9_b_c||tdqs9_b_c\  = M_A_CPU1_SB_DQS_DN<9>
  VSS41  = GND
  CB0_B  = M_A_CPU1_SB_CB<0>
  VSS42  = GND
  CB1_B  = M_A_CPU1_SB_CB<1>
  VSS43  = GND
  DQ0_B  = M_A_CPU1_SB_DQ<0>
  VSS44  = GND
  DQ1_B  = M_A_CPU1_SB_DQ<1>
  VSS45  = GND
  DQS0_B_T  = M_A_CPU1_SB_DQS_DP<0>
  DQS0_B_C  = M_A_CPU1_SB_DQS_DN<0>
  VSS46  = GND
  DQ4_B  = M_A_CPU1_SB_DQ<4>
  VSS47  = GND
  DQ5_B  = M_A_CPU1_SB_DQ<5>
  VSS48  = GND
  DQ8_B  = M_A_CPU1_SB_DQ<8>
  VSS49  = GND
  DQ9_B  = M_A_CPU1_SB_DQ<9>
  VSS50  = GND
  DQS1_B_T  = M_A_CPU1_SB_DQS_DP<1>
  DQS1_B_C  = M_A_CPU1_SB_DQS_DN<1>
  VSS51  = GND
  DQ12_B  = M_A_CPU1_SB_DQ<12>
  VSS52  = GND
  DQ13_B  = M_A_CPU1_SB_DQ<13>
  VSS53  = GND
  DQ16_B  = M_A_CPU1_SB_DQ<16>
  VSS54  = GND
  DQ17_B  = M_A_CPU1_SB_DQ<17>
  VSS55  = GND
  DQS2_B_T  = M_A_CPU1_SB_DQS_DP<2>
  DQS2_B_C  = M_A_CPU1_SB_DQS_DN<2>
  VSS56  = GND
  DQ20_B  = M_A_CPU1_SB_DQ<20>
  VSS57  = GND
  DQ21_B  = M_A_CPU1_SB_DQ<21>
  VSS58  = GND
  DQ24_B  = M_A_CPU1_SB_DQ<24>
  VSS59  = GND
  DQ25_B  = M_A_CPU1_SB_DQ<25>
  VSS60  = GND
  DQS3_B_T  = M_A_CPU1_SB_DQS_DP<3>
  DQS3_B_C  = M_A_CPU1_SB_DQS_DN<3>
  VSS61  = GND
  DQ28_B  = M_A_CPU1_SB_DQ<28>
  VSS62  = GND
  DQ29_B  = M_A_CPU1_SB_DQ<29>
  VSS63  = GND
  RFU1  = TP_CHA_CPU1_DIMM1_FRU_1
  VIN_BULK1  = P12V_S3_AUX_CPU1_NVDIMM
  VIN_BULK2  = P12V_S3_AUX_CPU1_NVDIMM
  \pwr_good||fail_n\  = PWRGD_CHA_CPU1_DIMM1
  HSA  = PD_CHA_CPU1_DIMM1_SAA
  RFU2  = TP_CHA_CPU1_DIMM1_FRU_2
  RFU3  = TP_CHA_CPU1_DIMM1_FRU_3
  VSS64  = GND
  DQ2_A  = M_A_CPU1_SA_DQ<2>
  VSS65  = GND
  DQ3_A  = M_A_CPU1_SA_DQ<3>
  VSS66  = GND
  \dqs5_a_c||tdqs5_a_c||dqs5_a_t||tdqs5_a_t\  = M_A_CPU1_SA_DQS_DN<5>
  \dqs5_a_t||tdqs5_a_t\  = M_A_CPU1_SA_DQS_DP<5>
  VSS67  = GND
  DQ6_A  = M_A_CPU1_SA_DQ<6>
  VSS68  = GND
  DQ7_A  = M_A_CPU1_SA_DQ<7>
  VSS69  = GND
  DQ10_A  = M_A_CPU1_SA_DQ<10>
  VSS70  = GND
  DQ11_A  = M_A_CPU1_SA_DQ<11>
  VSS71  = GND
  \dqs6_a_c||tdqs6_a_c||dqs6_a_t||tdqs6_a_t\  = M_A_CPU1_SA_DQS_DN<6>
  \dqs6_a_t||tdqs6_a_t\  = M_A_CPU1_SA_DQS_DP<6>
  VSS72  = GND
  DQ14_A  = M_A_CPU1_SA_DQ<14>
  VSS73  = GND
  DQ15_A  = M_A_CPU1_SA_DQ<15>
  VSS74  = GND
  DQ18_A  = M_A_CPU1_SA_DQ<18>
  VSS75  = GND
  DQ19_A  = M_A_CPU1_SA_DQ<19>
  VSS76  = GND
  \dqs7_a_c||tdqs7_a_c\  = M_A_CPU1_SA_DQS_DN<7>
  \dqs7_a_t||tdqs7_a_t\  = M_A_CPU1_SA_DQS_DP<7>
  VSS77  = GND
  DQ22_A  = M_A_CPU1_SA_DQ<22>
  VSS78  = GND
  DQ23_A  = M_A_CPU1_SA_DQ<23>
  VSS79  = GND
  DQ26_A  = M_A_CPU1_SA_DQ<26>
  VSS80  = GND
  DQ27_A  = M_A_CPU1_SA_DQ<27>
  VSS81  = GND
  \dqs8_a_c||tdqs8_a_c\  = M_A_CPU1_SA_DQS_DN<8>
  \dqs8_a_t||tdqs8_a_t\  = M_A_CPU1_SA_DQS_DP<8>
  VSS82  = GND
  DQ30_A  = M_A_CPU1_SA_DQ<30>
  VSS83  = GND
  DQ31_A  = M_A_CPU1_SA_DQ<31>
  VSS84  = GND
  CB2_A  = M_A_CPU1_SA_CB<2>
  VSS85  = GND
  CB3_A  = M_A_CPU1_SA_CB<3>
  VSS86  = GND
  \dqs9_a_c||tdqs9_a_c\  = M_A_CPU1_SA_DQS_DN<9>
  \dqs9_a_t||tdqs9_a_t\  = M_A_CPU1_SA_DQS_DP<9>
  VSS87  = GND
  CB6_A  = M_A_CPU1_SA_CB<6>
  VSS88  = GND
  CB7_A  = M_A_CPU1_SA_CB<7>
  VSS89  = GND
  RESET_N  = RST_M_AB_CPU1_FPGA_N
  VSS90  = GND
  CS1_A_N  = M_A_CPU1_SA_CS_N<1>
  VSS91  = GND
  CA1_A  = M_A_CPU1_SA_CA<1>
  VSS92  = GND
  CA3_A  = M_A_CPU1_SA_CA<3>
  VSS93  = GND
  CA5_A  = M_A_CPU1_SA_CA<5>
  VSS94  = GND
  CK_T  = M_A_CPU1_CLK_DP<0>
  CK_C  = M_A_CPU1_CLK_DN<0>
  VSS95  = GND
  RFU4  = TP_CHA_CPU1_DIMM1_FRU_4
  CA1_B  = M_A_CPU1_SB_CA<1>
  VSS96  = GND
  CA3_B  = M_A_CPU1_SB_CA<3>
  VSS97  = GND
  CA5_B  = M_A_CPU1_SB_CA<5>
  VSS98  = GND
  PAR_B  = M_A_CPU1_SB_PAR
  VSS99  = GND
  CS1_B_N  = M_A_CPU1_SB_CS_N<1>
  VSS100  = GND
  RFU5  = TP_CHA_CPU1_DIMM1_FRU_5
  RFU6  = TP_CHA_CPU1_DIMM1_FRU_6
  VSS101  = GND
  CB6_B  = M_A_CPU1_SB_CB<6>
  VSS102  = GND
  CB7_B  = M_A_CPU1_SB_CB<7>
  VSS103  = GND
  DQS4_B_C  = M_A_CPU1_SB_DQS_DN<4>
  DQS4_B_T  = M_A_CPU1_SB_DQS_DP<4>
  VSS104  = GND
  CB2_B  = M_A_CPU1_SB_CB<2>
  VSS105  = GND
  CB3_B  = M_A_CPU1_SB_CB<3>
  VSS106  = GND
  DQ2_B  = M_A_CPU1_SB_DQ<2>
  VSS107  = GND
  DQ3_B  = M_A_CPU1_SB_DQ<3>
  VSS108  = GND
  \dqs5_b_c||tdqs5_b_c\  = M_A_CPU1_SB_DQS_DN<5>
  \dqs5_b_t||tdqs5_b_t\  = M_A_CPU1_SB_DQS_DP<5>
  VSS109  = GND
  DQ6_B  = M_A_CPU1_SB_DQ<6>
  VSS110  = GND
  DQ7_B  = M_A_CPU1_SB_DQ<7>
  VSS111  = GND
  DQ10_B  = M_A_CPU1_SB_DQ<10>
  VSS112  = GND
  DQ11_B  = M_A_CPU1_SB_DQ<11>
  VSS113  = GND
  \dqs6_b_c||tdqs6_b_c\  = M_A_CPU1_SB_DQS_DN<6>
  \dqs6_b_t||tdqs6_b_t\  = M_A_CPU1_SB_DQS_DP<6>
  VSS114  = GND
  DQ14_B  = M_A_CPU1_SB_DQ<14>
  VSS115  = GND
  DQ15_B  = M_A_CPU1_SB_DQ<15>
  VSS116  = GND
  DQ18_B  = M_A_CPU1_SB_DQ<18>
  VSS117  = GND
  DQ19_B  = M_A_CPU1_SB_DQ<19>
  VSS118  = GND
  \dqs7_b_c||tdqs7_b_c\  = M_A_CPU1_SB_DQS_DN<7>
  \dqs7_b_t||tdqs7_b_t\  = M_A_CPU1_SB_DQS_DP<7>
  VSS119  = GND
  DQ22_B  = M_A_CPU1_SB_DQ<22>
  VSS120  = GND
  DQ23_B  = M_A_CPU1_SB_DQ<23>
  VSS121  = GND
  DQ26_B  = M_A_CPU1_SB_DQ<26>
  VSS122  = GND
  DQ27_B  = M_A_CPU1_SB_DQ<27>
  VSS123  = GND
  \dqs8_b_c||tdqs8_b_c\  = M_A_CPU1_SB_DQS_DN<8>
  \dqs8_b_t||tdqs8_b_t\  = M_A_CPU1_SB_DQS_DP<8>
  VSS124  = GND
  DQ30_B  = M_A_CPU1_SB_DQ<30>
  VSS125  = GND
  DQ31_B  = M_A_CPU1_SB_DQ<31>
  VSS126  = GND
  G1  = GND
  G2  = GND
  G3  = GND

(kicad_pcb
	(version 20260206)
	(generator "pcbnew")
	(generator_version "10.0")
	(general
		(thickness 1.6)
		(legacy_teardrops no)
	)
	(paper "A4")
	(title_block
		(title "03242023_DA0F0TMBIJ0_F0T_Motherboard_J_brd_V01_OCP.brd")
		(comment 1 "Grand Teton / footprint 1335 of 6105 (J17), pads 275-291 of 291")
	)
	(layers
		(0 "F.Cu" signal "TOP")
		(4 "In1.Cu" signal "GND")
		(6 "In2.Cu" signal "IN1")
		(8 "In3.Cu" signal "GND1")
		(10 "In4.Cu" signal "IN2")
		(12 "In5.Cu" signal "GND2")
		(14 "In6.Cu" signal "IN3")
		(16 "In7.Cu" signal "GND3")
		(18 "In8.Cu" signal "VCC")
		(20 "In9.Cu" signal "VCC1")
		(22 "In10.Cu" signal "GND4")
		(24 "In11.Cu" signal "IN4")
		(26 "In12.Cu" signal "GND5")
		(28 "In13.Cu" signal "IN5")
		(30 "In14.Cu" signal "GND6")
		(32 "In15.Cu" signal "IN6")
		(34 "In16.Cu" signal "GND7")
		(2 "B.Cu" signal "BOTTOM")
		(9 "F.Adhes" user "F.Adhesive")
		(11 "B.Adhes" user "B.Adhesive")
		(13 "F.Paste" user "Package Geometry/Pastemask Top")
		(15 "B.Paste" user "Package Geometry/Pastemask Bottom")
		(5 "F.SilkS" user "Ref Des/Silkscreen Top")
		(7 "B.SilkS" user "Ref Des/Silkscreen Bottom")
		(1 "F.Mask" user "Board Geometry/Soldermask Top")
		(3 "B.Mask" user "Board Geometry/Soldermask Bottom")
		(17 "Dwgs.User" user "User.Drawings")
		(19 "Cmts.User" user "User.Comments")
		(21 "Eco1.User" user "User.Eco1")
		(23 "Eco2.User" user "User.Eco2")
		(25 "Edge.Cuts" user "Board Geometry/Outline")
		(27 "Margin" user)
		(31 "F.CrtYd" user "Package Geometry/Place Bound Top")
		(29 "B.CrtYd" user "Package Geometry/Place Bound Bottom")
		(35 "F.Fab" user "Ref Des/Assembly Top")
		(33 "B.Fab" user "Ref Des/Assembly Bottom")
	)
	(footprint ""
		(layer "F.Cu")
		(at 55.45328 -258.091686)
		(property "Reference" "J17"
			(at -0.178562 -81.717134 0)
			(unlocked yes)
			(layer "F.SilkS")
			(effects
				(font
					(size 0.7874 0.5842)
					(thickness 0.1524)
				)
				(justify left)
			)
		)
		(property "Value" ""
			(at 0 0 0)
			(layer "F.Fab")
			(effects
				(font
					(size 1.27 1.27)
				)
			)
		)
		(duplicate_pad_numbers_are_jumpers no)
		(pad "275" smd rect
			(at 2.050034 52.274978 270)
			(size 0.519938 1.4986)
			(layers "F.Cu" "F.Mask" "F.Paste")
			(net "GND")
		)
		(pad "276" smd rect
			(at 2.050034 53.125116 270)
			(size 0.519938 1.4986)
			(layers "F.Cu" "F.Mask" "F.Paste")
			(net "M_A_CPU1_SB_DQ<23>")
		)
		(pad "277" smd rect
			(at 2.050034 53.975 270)
			(size 0.519938 1.4986)
			(layers "F.Cu" "F.Mask" "F.Paste")
			(net "GND")
		)
		(pad "278" smd rect
			(at 2.050034 54.824884 270)
			(size 0.519938 1.4986)
			(layers "F.Cu" "F.Mask" "F.Paste")
			(net "M_A_CPU1_SB_DQ<26>")
		)
		(pad "279" smd rect
			(at 2.050034 55.675022 270)
			(size 0.519938 1.4986)
			(layers "F.Cu" "F.Mask" "F.Paste")
			(net "GND")
		)
		(pad "280" smd rect
			(at 2.050034 56.524906 270)
			(size 0.519938 1.4986)
			(layers "F.Cu" "F.Mask" "F.Paste")
			(net "M_A_CPU1_SB_DQ<27>")
		)
		(pad "281" smd rect
			(at 2.050034 57.375044 270)
			(size 0.519938 1.4986)
			(layers "F.Cu" "F.Mask" "F.Paste")
			(net "GND")
		)
		(pad "282" smd rect
			(at 2.050034 58.224928 270)
			(size 0.519938 1.4986)
			(layers "F.Cu" "F.Mask" "F.Paste")
			(net "M_A_CPU1_SB_DQS_DN<8>")
		)
		(pad "283" smd rect
			(at 2.050034 59.075066 270)
			(size 0.519938 1.4986)
			(layers "F.Cu" "F.Mask" "F.Paste")
			(net "M_A_CPU1_SB_DQS_DP<8>")
		)
		(pad "284" smd rect
			(at 2.050034 59.92495 270)
			(size 0.519938 1.4986)
			(layers "F.Cu" "F.Mask" "F.Paste")
			(net "GND")
		)
		(pad "285" smd rect
			(at 2.050034 60.775088 270)
			(size 0.519938 1.4986)
			(layers "F.Cu" "F.Mask" "F.Paste")
			(net "M_A_CPU1_SB_DQ<30>")
		)
		(pad "286" smd rect
			(at 2.050034 61.624972 270)
			(size 0.519938 1.4986)
			(layers "F.Cu" "F.Mask" "F.Paste")
			(net "GND")
		)
		(pad "287" smd rect
			(at 2.050034 62.47511 270)
			(size 0.519938 1.4986)
			(layers "F.Cu" "F.Mask" "F.Paste")
			(net "M_A_CPU1_SB_DQ<31>")
		)
		(pad "288" smd rect
			(at 2.050034 63.324994 270)
			(size 0.519938 1.4986)
			(layers "F.Cu" "F.Mask" "F.Paste")
			(net "GND")
		)
		(pad "G1" thru_hole oval
			(at 0 -68.97497)
			(size 2.8194 1.5748)
			(drill oval 2.4384 1.1938)
			(layers "*.Cu" "*.Mask")
			(remove_unused_layers no)
			(net "GND")
			(clearance 0.127)
			(thermal_gap 0.127)
		)
		(pad "G2" thru_hole oval
			(at 0 3.875024)
			(size 2.8194 1.5748)
			(drill oval 2.4384 1.1938)
			(layers "*.Cu" "*.Mask")
			(remove_unused_layers no)
			(net "GND")
			(clearance 0.127)
			(thermal_gap 0.127)
		)
		(pad "G3" thru_hole oval
			(at 0 68.97497)
			(size 2.8194 1.5748)
			(drill oval 2.4384 1.1938)
			(layers "*.Cu" "*.Mask")
			(remove_unused_layers no)
			(net "GND")
			(clearance 0.127)
			(thermal_gap 0.127)
		)
	)
)
